# S9S_MB_2U (Grand Teton) — schematic netlist excerpt (pin names and nets, part order shuffled) for the footprints in the layout excerpt that follows; sources: Cadence DE-HDL packaged netlist, KiCad conversion of 03242023_DA0F0TMBIJ0_F0T_Motherboard_J_brd_V01_OCP.brd

C2287  Q_CAP  0.01UF 50V 10% X7R  pkg C0402  page 263 : A = PWRGD_P1V8_PCH_AUX ; B = GND
C917  Q_CAP_DIFFBUS  DIFF BUS_0.22UF 6.3V 20% X6S  pkg C0201  page 173 : \1\ = P5E_CPU0_PE0_TX_C_DP<8> ; \2\ = P5E_CPU0_PE0_TX_DP<8>
C682  Q_CAP_DIFFBUS  DIFF BUS_0.22UF 6.3V 20% X6S  pkg C0201  page 177 : \1\ = P5E_CPU1_PE4_TX_C_DN<13> ; \2\ = P5E_CPU1_PE4_TX_DN<13>

(kicad_pcb
	(version 20260206)
	(generator "pcbnew")
	(generator_version "10.0")
	(general
		(thickness 1.6)
		(legacy_teardrops no)
	)
	(paper "A4")
	(title_block
		(title "03242023_DA0F0TMBIJ0_F0T_Motherboard_J_brd_V01_OCP.brd")
		(comment 1 "Grand Teton / footprints 1230-1232 of 6105")
	)
	(layers
		(0 "F.Cu" signal "TOP")
		(4 "In1.Cu" signal "GND")
		(6 "In2.Cu" signal "IN1")
		(8 "In3.Cu" signal "GND1")
		(10 "In4.Cu" signal "IN2")
		(12 "In5.Cu" signal "GND2")
		(14 "In6.Cu" signal "IN3")
		(16 "In7.Cu" signal "GND3")
		(18 "In8.Cu" signal "VCC")
		(20 "In9.Cu" signal "VCC1")
		(22 "In10.Cu" signal "GND4")
		(24 "In11.Cu" signal "IN4")
		(26 "In12.Cu" signal "GND5")
		(28 "In13.Cu" signal "IN5")
		(30 "In14.Cu" signal "GND6")
		(32 "In15.Cu" signal "IN6")
		(34 "In16.Cu" signal "GND7")
		(2 "B.Cu" signal "BOTTOM")
		(9 "F.Adhes" user "F.Adhesive")
		(11 "B.Adhes" user "B.Adhesive")
		(13 "F.Paste" user "Package Geometry/Pastemask Top")
		(15 "B.Paste" user "Package Geometry/Pastemask Bottom")
		(5 "F.SilkS" user "Ref Des/Silkscreen Top")
		(7 "B.SilkS" user "Ref Des/Silkscreen Bottom")
		(1 "F.Mask" user "Board Geometry/Soldermask Top")
		(3 "B.Mask" user "Board Geometry/Soldermask Bottom")
		(17 "Dwgs.User" user "User.Drawings")
		(19 "Cmts.User" user "User.Comments")
		(21 "Eco1.User" user "User.Eco1")
		(23 "Eco2.User" user "User.Eco2")
		(25 "Edge.Cuts" user "Board Geometry/Outline")
		(27 "Margin" user)
		(31 "F.CrtYd" user "Package Geometry/Place Bound Top")
		(29 "B.CrtYd" user "Package Geometry/Place Bound Bottom")
		(35 "F.Fab" user "Ref Des/Assembly Top")
		(33 "B.Fab" user "Ref Des/Assembly Bottom")
	)
	(footprint ""
		(layer "F.Cu")
		(at 89.122758 -408.517344 -90)
		(property "Reference" "C682"
			(at 0 0 270)
			(layer "F.SilkS")
			(hide yes)
			(effects
				(font
					(size 1.27 1.27)
				)
			)
		)
		(property "Value" ""
			(at 0 0 270)
			(layer "F.Fab")
			(effects
				(font
					(size 1.27 1.27)
				)
			)
		)
		(duplicate_pad_numbers_are_jumpers no)
		(fp_line
			(start -0.299974 0.150114)
			(end -0.299974 -0.150114)
			(stroke
				(width 0.1)
				(type default)
			)
			(layer "F.Fab")
		)
		(fp_line
			(start 0.299974 0.150114)
			(end -0.299974 0.150114)
			(stroke
				(width 0.1)
				(type default)
			)
			(layer "F.Fab")
		)
		(fp_line
			(start -0.299974 -0.150114)
			(end 0.299974 -0.150114)
			(stroke
				(width 0.1)
				(type default)
			)
			(layer "F.Fab")
		)
		(fp_line
			(start 0.299974 -0.150114)
			(end 0.299974 0.150114)
			(stroke
				(width 0.1)
				(type default)
			)
			(layer "F.Fab")
		)
		(pad "1" smd rect
			(at -0.2667 0 270)
			(size 0.3048 0.381)
			(layers "F.Cu" "F.Mask" "F.Paste")
			(net "P5E_CPU1_PE4_TX_C_DN<13>")
		)
		(pad "2" smd rect
			(at 0.2667 0 270)
			(size 0.3048 0.381)
			(layers "F.Cu" "F.Mask" "F.Paste")
			(net "P5E_CPU1_PE4_TX_DN<13>")
		)
	)
	(footprint ""
		(layer "F.Cu")
		(at 327.657968 -408.517344 -90)
		(property "Reference" "C917"
			(at 0 0 270)
			(layer "F.SilkS")
			(hide yes)
			(effects
				(font
					(size 1.27 1.27)
				)
			)
		)
		(property "Value" ""
			(at 0 0 270)
			(layer "F.Fab")
			(effects
				(font
					(size 1.27 1.27)
				)
			)
		)
		(duplicate_pad_numbers_are_jumpers no)
		(fp_line
			(start -0.299974 0.150114)
			(end -0.299974 -0.150114)
			(stroke
				(width 0.1)
				(type default)
			)
			(layer "F.Fab")
		)
		(fp_line
			(start 0.299974 0.150114)
			(end -0.299974 0.150114)
			(stroke
				(width 0.1)
				(type default)
			)
			(layer "F.Fab")
		)
		(fp_line
			(start -0.299974 -0.150114)
			(end 0.299974 -0.150114)
			(stroke
				(width 0.1)
				(type default)
			)
			(layer "F.Fab")
		)
		(fp_line
			(start 0.299974 -0.150114)
			(end 0.299974 0.150114)
			(stroke
				(width 0.1)
				(type default)
			)
			(layer "F.Fab")
		)
		(pad "1" smd rect
			(at -0.2667 0 270)
			(size 0.3048 0.381)
			(layers "F.Cu" "F.Mask" "F.Paste")
			(net "P5E_CPU0_PE0_TX_C_DP<8>")
		)
		(pad "2" smd rect
			(at 0.2667 0 270)
			(size 0.3048 0.381)
			(layers "F.Cu" "F.Mask" "F.Paste")
			(net "P5E_CPU0_PE0_TX_DP<8>")
		)
	)
	(footprint ""
		(layer "F.Cu")
		(at 385.637532 -71.362824 180)
		(property "Reference" "C2287"
			(at 0 0 180)
			(layer "F.SilkS")
			(hide yes)
			(effects
				(font
					(size 1.27 1.27)
				)
			)
		)
		(property "Value" ""
			(at 0 0 180)
			(layer "F.Fab")
			(effects
				(font
					(size 1.27 1.27)
				)
			)
		)
		(duplicate_pad_numbers_are_jumpers no)
		(fp_line
			(start 0.7874 0.4064)
			(end -0.7874 0.4064)
			(stroke
				(width 0.1524)
				(type default)
			)
			(layer "F.SilkS")
		)
		(fp_line
			(start 0.7874 -0.4064)
			(end 0.7874 0.4064)
			(stroke
				(width 0.1524)
				(type default)
			)
			(layer "F.SilkS")
		)
		(fp_line
			(start -0.7874 0.4064)
			(end -0.7874 -0.4064)
			(stroke
				(width 0.1524)
				(type default)
			)
			(layer "F.SilkS")
		)
		(fp_line
			(start -0.7874 -0.4064)
			(end 0.7874 -0.4064)
			(stroke
				(width 0.1524)
				(type default)
			)
			(layer "F.SilkS")
		)
		(fp_line
			(start 0.67945 0.3048)
			(end 0.120396 0.3048)
			(stroke
				(width 0.1)
				(type default)
			)
			(layer "F.Fab")
		)
		(fp_line
			(start 0.67945 -0.3048)
			(end 0.67945 0.3048)
			(stroke
				(width 0.1)
				(type default)
			)
			(layer "F.Fab")
		)
		(fp_line
			(start 0.12065 -0.2794)
			(end 0.12065 -0.3048)
			(stroke
				(width 0.1)
				(type default)
			)
			(layer "F.Fab")
		)
		(fp_line
			(start 0.12065 -0.3048)
			(end 0.67945 -0.3048)
			(stroke
				(width 0.1)
				(type default)
			)
			(layer "F.Fab")
		)
		(fp_line
			(start 0.120396 0.3048)
			(end 0.120396 0.2794)
			(stroke
				(width 0.1)
				(type default)
			)
			(layer "F.Fab")
		)
		(fp_line
			(start 0.120396 0.2794)
			(end -0.12065 0.2794)
			(stroke
				(width 0.1)
				(type default)
			)
			(layer "F.Fab")
		)
		(fp_line
			(start -0.12065 0.3048)
			(end -0.67945 0.3048)
			(stroke
				(width 0.1)
				(type default)
			)
			(layer "F.Fab")
		)
		(fp_line
			(start -0.12065 0.2794)
			(end -0.12065 0.3048)
			(stroke
				(width 0.1)
				(type default)
			)
			(layer "F.Fab")
		)
		(fp_line
			(start -0.12065 -0.2794)
			(end 0.12065 -0.2794)
			(stroke
				(width 0.1)
				(type default)
			)
			(layer "F.Fab")
		)
		(fp_line
			(start -0.12065 -0.305054)
			(end -0.12065 -0.2794)
			(stroke
				(width 0.1)
				(type default)
			)
			(layer "F.Fab")
		)
		(fp_line
			(start -0.67945 0.3048)
			(end -0.67945 -0.305054)
			(stroke
				(width 0.1)
				(type default)
			)
			(layer "F.Fab")
		)
		(fp_line
			(start -0.67945 -0.305054)
			(end -0.12065 -0.305054)
			(stroke
				(width 0.1)
				(type default)
			)
			(layer "F.Fab")
		)
		(pad "1" smd circle
			(at -0.40005 0 180)
			(size 0 0)
			(layers "F.Cu" "F.Mask" "F.Paste")
			(net "PWRGD_P1V8_PCH_AUX")
		)
		(pad "2" smd circle
			(at 0.40005 0 180)
			(size 0 0)
			(layers "F.Cu" "F.Mask" "F.Paste")
			(net "GND")
		)
	)
)
